(kicad_pcb
	(version 20260206)
	(generator "pcbnew")
	(generator_version "10.0")
	(general
		(thickness 1.6)
		(legacy_teardrops no)
	)
	(paper "A4")
	(title_block
		(title "01162023_DA0F0TEBIF0_F0T_Expander_BD_F_brd_V02_OCP.brd")
		(comment 1 "Grand Teton / footprint 5622 of 9728 (PEX2), pads 1190-1307 of 2397")
	)
	(layers
		(0 "F.Cu" signal "TOP")
		(4 "In1.Cu" signal "GND")
		(6 "In2.Cu" signal "VCC")
		(8 "In3.Cu" signal "VCC1")
		(10 "In4.Cu" signal "GND1")
		(12 "In5.Cu" signal "IN1")
		(14 "In6.Cu" signal "GND2")
		(16 "In7.Cu" signal "IN2")
		(18 "In8.Cu" signal "GND3")
		(20 "In9.Cu" signal "IN3")
		(22 "In10.Cu" signal "GND4")
		(24 "In11.Cu" signal "IN4")
		(26 "In12.Cu" signal "GND5")
		(28 "In13.Cu" signal "IN5")
		(30 "In14.Cu" signal "GND6")
		(32 "In15.Cu" signal "IN6")
		(34 "In16.Cu" signal "GND7")
		(2 "B.Cu" signal "BOTTOM")
		(9 "F.Adhes" user "F.Adhesive")
		(11 "B.Adhes" user "B.Adhesive")
		(13 "F.Paste" user "Package Geometry/Pastemask Top")
		(15 "B.Paste" user "Package Geometry/Pastemask Bottom")
		(5 "F.SilkS" user "Ref Des/Silkscreen Top")
		(7 "B.SilkS" user "Ref Des/Silkscreen Bottom")
		(1 "F.Mask" user "Board Geometry/Soldermask Top")
		(3 "B.Mask" user "Board Geometry/Soldermask Bottom")
		(17 "Dwgs.User" user "User.Drawings")
		(19 "Cmts.User" user "User.Comments")
		(21 "Eco1.User" user "User.Eco1")
		(23 "Eco2.User" user "User.Eco2")
		(25 "Edge.Cuts" user "Board Geometry/Outline")
		(27 "Margin" user)
		(31 "F.CrtYd" user "Package Geometry/Place Bound Top")
		(29 "B.CrtYd" user "Package Geometry/Place Bound Bottom")
		(35 "F.Fab" user "Ref Des/Assembly Top")
		(33 "B.Fab" user "Ref Des/Assembly Bottom")
	)
	(footprint ""
		(layer "F.Cu")
		(at 291.84981 -295.89984)
		(property "Reference" "PEX2"
			(at -3.35153 35.56762 0)
			(unlocked yes)
			(layer "F.SilkS")
			(effects
				(font
					(size 2.032 1.524)
					(thickness 0.1524)
				)
				(justify left)
			)
		)
		(property "Value" ""
			(at 0 0 0)
			(layer "F.Fab")
			(effects
				(font
					(size 1.27 1.27)
				)
			)
		)
		(duplicate_pad_numbers_are_jumpers no)
		(pad "BC16" smd circle
			(at -8.549894 17.100042)
			(size 0.4572 0.4572)
			(layers "F.Cu" "F.Mask" "F.Paste")
			(net "GND")
		)
		(pad "BC17" smd circle
			(at -7.599934 17.100042)
			(size 0.4572 0.4572)
			(layers "F.Cu" "F.Mask" "F.Paste")
			(net "P5E_PEX2_STN2_TX_DP<39>")
		)
		(pad "BC18" smd circle
			(at -6.649974 17.100042)
			(size 0.4572 0.4572)
			(layers "F.Cu" "F.Mask" "F.Paste")
			(net "GND")
		)
		(pad "BC19" smd circle
			(at -5.700014 17.100042)
			(size 0.4572 0.4572)
			(layers "F.Cu" "F.Mask" "F.Paste")
			(net "P5E_PEX2_STN2_TX_DP<37>")
		)
		(pad "BC20" smd circle
			(at -4.750054 17.100042)
			(size 0.4572 0.4572)
			(layers "F.Cu" "F.Mask" "F.Paste")
			(net "GND")
		)
		(pad "BC21" smd circle
			(at -3.800094 17.100042)
			(size 0.4572 0.4572)
			(layers "F.Cu" "F.Mask" "F.Paste")
			(net "P5E_PEX2_STN2_TX_DP<35>")
		)
		(pad "BC22" smd circle
			(at -2.84988 17.100042)
			(size 0.4572 0.4572)
			(layers "F.Cu" "F.Mask" "F.Paste")
			(net "GND")
		)
		(pad "BC23" smd circle
			(at -1.89992 17.100042)
			(size 0.4572 0.4572)
			(layers "F.Cu" "F.Mask" "F.Paste")
			(net "P5E_PEX2_STN2_TX_DP<33>")
		)
		(pad "BC24" smd circle
			(at -0.94996 17.100042)
			(size 0.4572 0.4572)
			(layers "F.Cu" "F.Mask" "F.Paste")
			(net "GND")
		)
		(pad "BC25" smd circle
			(at 0 17.100042)
			(size 0.4572 0.4572)
			(layers "F.Cu" "F.Mask" "F.Paste")
			(net "P5E_PEX2_STN1_TX_DP<16>")
		)
		(pad "BC26" smd circle
			(at 0.94996 17.100042)
			(size 0.4572 0.4572)
			(layers "F.Cu" "F.Mask" "F.Paste")
			(net "GND")
		)
		(pad "BC27" smd circle
			(at 1.89992 17.100042)
			(size 0.4572 0.4572)
			(layers "F.Cu" "F.Mask" "F.Paste")
			(net "P5E_PEX2_STN1_TX_DP<18>")
		)
		(pad "BC28" smd circle
			(at 2.84988 17.100042)
			(size 0.4572 0.4572)
			(layers "F.Cu" "F.Mask" "F.Paste")
			(net "GND")
		)
		(pad "BC29" smd circle
			(at 3.800094 17.100042)
			(size 0.4572 0.4572)
			(layers "F.Cu" "F.Mask" "F.Paste")
			(net "P5E_PEX2_STN1_TX_DP<20>")
		)
		(pad "BC30" smd circle
			(at 4.750054 17.100042)
			(size 0.4572 0.4572)
			(layers "F.Cu" "F.Mask" "F.Paste")
			(net "GND")
		)
		(pad "BC31" smd circle
			(at 5.700014 17.100042)
			(size 0.4572 0.4572)
			(layers "F.Cu" "F.Mask" "F.Paste")
			(net "P5E_PEX2_STN1_TX_DP<22>")
		)
		(pad "BC32" smd circle
			(at 6.649974 17.100042)
			(size 0.4572 0.4572)
			(layers "F.Cu" "F.Mask" "F.Paste")
			(net "GND")
		)
		(pad "BC33" smd circle
			(at 7.599934 17.100042)
			(size 0.4572 0.4572)
			(layers "F.Cu" "F.Mask" "F.Paste")
			(net "P5E_PEX2_STN1_TX_DP<24>")
		)
		(pad "BC34" smd circle
			(at 8.549894 17.100042)
			(size 0.4572 0.4572)
			(layers "F.Cu" "F.Mask" "F.Paste")
			(net "GND")
		)
		(pad "BC35" smd circle
			(at 9.500108 17.100042)
			(size 0.4572 0.4572)
			(layers "F.Cu" "F.Mask" "F.Paste")
			(net "P5E_PEX2_STN1_TX_DP<26>")
		)
		(pad "BC36" smd circle
			(at 10.450068 17.100042)
			(size 0.4572 0.4572)
			(layers "F.Cu" "F.Mask" "F.Paste")
			(net "GND")
		)
		(pad "BC37" smd circle
			(at 11.400028 17.100042)
			(size 0.4572 0.4572)
			(layers "F.Cu" "F.Mask" "F.Paste")
			(net "P5E_PEX2_STN1_TX_DP<28>")
		)
		(pad "BC38" smd circle
			(at 12.349988 17.100042)
			(size 0.4572 0.4572)
			(layers "F.Cu" "F.Mask" "F.Paste")
			(net "GND")
		)
		(pad "BC39" smd circle
			(at 13.299948 17.100042)
			(size 0.4572 0.4572)
			(layers "F.Cu" "F.Mask" "F.Paste")
			(net "P5E_PEX2_STN1_TX_DP<30>")
		)
		(pad "BC40" smd circle
			(at 14.249908 17.100042)
			(size 0.4572 0.4572)
			(layers "F.Cu" "F.Mask" "F.Paste")
			(net "GND")
		)
		(pad "BC41" smd circle
			(at 15.200122 17.100042)
			(size 0.4572 0.4572)
			(layers "F.Cu" "F.Mask" "F.Paste")
			(net "P5E_PEX2_STN0_TX_DP<15>")
		)
		(pad "BC42" smd circle
			(at 16.150082 17.100042)
			(size 0.4572 0.4572)
			(layers "F.Cu" "F.Mask" "F.Paste")
			(net "GND")
		)
		(pad "BC43" smd circle
			(at 17.100042 17.100042)
			(size 0.4572 0.4572)
			(layers "F.Cu" "F.Mask" "F.Paste")
			(net "P5E_PEX2_STN0_TX_DP<13>")
		)
		(pad "BC44" smd circle
			(at 18.050002 17.100042)
			(size 0.4572 0.4572)
			(layers "F.Cu" "F.Mask" "F.Paste")
			(net "GND")
		)
		(pad "BC45" smd circle
			(at 18.999962 17.100042)
			(size 0.4572 0.4572)
			(layers "F.Cu" "F.Mask" "F.Paste")
			(net "P5E_PEX2_STN0_TX_DP<11>")
		)
		(pad "BC46" smd circle
			(at 19.949922 17.100042)
			(size 0.4572 0.4572)
			(layers "F.Cu" "F.Mask" "F.Paste")
			(net "GND")
		)
		(pad "BC47" smd circle
			(at 20.899882 17.100042)
			(size 0.4572 0.4572)
			(layers "F.Cu" "F.Mask" "F.Paste")
			(net "P5E_PEX2_STN0_TX_DP<9>")
		)
		(pad "BC48" smd circle
			(at 21.850096 17.100042)
			(size 0.4572 0.4572)
			(layers "F.Cu" "F.Mask" "F.Paste")
			(net "GND")
		)
		(pad "BC49" smd circle
			(at 22.800056 17.100042)
			(size 0.4572 0.4572)
			(layers "F.Cu" "F.Mask" "F.Paste")
			(net "GND")
		)
		(pad "BD1" smd circle
			(at -22.800056 18.050002)
			(size 0.4572 0.4572)
			(layers "F.Cu" "F.Mask" "F.Paste")
			(net "GND")
		)
		(pad "BD2" smd circle
			(at -21.850096 18.050002)
			(size 0.4572 0.4572)
			(layers "F.Cu" "F.Mask" "F.Paste")
			(net "GND")
		)
		(pad "BD3" smd circle
			(at -20.899882 18.050002)
			(size 0.4572 0.4572)
			(layers "F.Cu" "F.Mask" "F.Paste")
			(net "Net_1729")
		)
		(pad "BD4" smd circle
			(at -19.949922 18.050002)
			(size 0.4572 0.4572)
			(layers "F.Cu" "F.Mask" "F.Paste")
			(net "GND")
		)
		(pad "BD5" smd circle
			(at -18.999962 18.050002)
			(size 0.4572 0.4572)
			(layers "F.Cu" "F.Mask" "F.Paste")
			(net "Net_1396")
		)
		(pad "BD6" smd circle
			(at -18.050002 18.050002)
			(size 0.4572 0.4572)
			(layers "F.Cu" "F.Mask" "F.Paste")
			(net "GND")
		)
		(pad "BD7" smd circle
			(at -17.100042 18.050002)
			(size 0.4572 0.4572)
			(layers "F.Cu" "F.Mask" "F.Paste")
			(net "Net_1716")
		)
		(pad "BD8" smd circle
			(at -16.150082 18.050002)
			(size 0.4572 0.4572)
			(layers "F.Cu" "F.Mask" "F.Paste")
			(net "GND")
		)
		(pad "BD9" smd circle
			(at -15.200122 18.050002)
			(size 0.4572 0.4572)
			(layers "F.Cu" "F.Mask" "F.Paste")
			(net "P5E_PEX2_STN2_TX_DN<47>")
		)
		(pad "BD10" smd circle
			(at -14.249908 18.050002)
			(size 0.4572 0.4572)
			(layers "F.Cu" "F.Mask" "F.Paste")
			(net "GND")
		)
		(pad "BD11" smd circle
			(at -13.299948 18.050002)
			(size 0.4572 0.4572)
			(layers "F.Cu" "F.Mask" "F.Paste")
			(net "P5E_PEX2_STN2_TX_DN<45>")
		)
		(pad "BD12" smd circle
			(at -12.349988 18.050002)
			(size 0.4572 0.4572)
			(layers "F.Cu" "F.Mask" "F.Paste")
			(net "GND")
		)
		(pad "BD13" smd circle
			(at -11.400028 18.050002)
			(size 0.4572 0.4572)
			(layers "F.Cu" "F.Mask" "F.Paste")
			(net "P5E_PEX2_STN2_TX_DN<43>")
		)
		(pad "BD14" smd circle
			(at -10.450068 18.050002)
			(size 0.4572 0.4572)
			(layers "F.Cu" "F.Mask" "F.Paste")
			(net "GND")
		)
		(pad "BD15" smd circle
			(at -9.500108 18.050002)
			(size 0.4572 0.4572)
			(layers "F.Cu" "F.Mask" "F.Paste")
			(net "P5E_PEX2_STN2_TX_DN<41>")
		)
		(pad "BD16" smd circle
			(at -8.549894 18.050002)
			(size 0.4572 0.4572)
			(layers "F.Cu" "F.Mask" "F.Paste")
			(net "GND")
		)
		(pad "BD17" smd circle
			(at -7.599934 18.050002)
			(size 0.4572 0.4572)
			(layers "F.Cu" "F.Mask" "F.Paste")
			(net "P5E_PEX2_STN2_TX_DN<39>")
		)
		(pad "BD18" smd circle
			(at -6.649974 18.050002)
			(size 0.4572 0.4572)
			(layers "F.Cu" "F.Mask" "F.Paste")
			(net "GND")
		)
		(pad "BD19" smd circle
			(at -5.700014 18.050002)
			(size 0.4572 0.4572)
			(layers "F.Cu" "F.Mask" "F.Paste")
			(net "P5E_PEX2_STN2_TX_DN<37>")
		)
		(pad "BD20" smd circle
			(at -4.750054 18.050002)
			(size 0.4572 0.4572)
			(layers "F.Cu" "F.Mask" "F.Paste")
			(net "GND")
		)
		(pad "BD21" smd circle
			(at -3.800094 18.050002)
			(size 0.4572 0.4572)
			(layers "F.Cu" "F.Mask" "F.Paste")
			(net "P5E_PEX2_STN2_TX_DN<35>")
		)
		(pad "BD22" smd circle
			(at -2.84988 18.050002)
			(size 0.4572 0.4572)
			(layers "F.Cu" "F.Mask" "F.Paste")
			(net "GND")
		)
		(pad "BD23" smd circle
			(at -1.89992 18.050002)
			(size 0.4572 0.4572)
			(layers "F.Cu" "F.Mask" "F.Paste")
			(net "P5E_PEX2_STN2_TX_DN<33>")
		)
		(pad "BD24" smd circle
			(at -0.94996 18.050002)
			(size 0.4572 0.4572)
			(layers "F.Cu" "F.Mask" "F.Paste")
			(net "GND")
		)
		(pad "BD25" smd circle
			(at 0 18.050002)
			(size 0.4572 0.4572)
			(layers "F.Cu" "F.Mask" "F.Paste")
			(net "P5E_PEX2_STN1_TX_DN<16>")
		)
		(pad "BD26" smd circle
			(at 0.94996 18.050002)
			(size 0.4572 0.4572)
			(layers "F.Cu" "F.Mask" "F.Paste")
			(net "GND")
		)
		(pad "BD27" smd circle
			(at 1.89992 18.050002)
			(size 0.4572 0.4572)
			(layers "F.Cu" "F.Mask" "F.Paste")
			(net "P5E_PEX2_STN1_TX_DN<18>")
		)
		(pad "BD28" smd circle
			(at 2.84988 18.050002)
			(size 0.4572 0.4572)
			(layers "F.Cu" "F.Mask" "F.Paste")
			(net "GND")
		)
		(pad "BD29" smd circle
			(at 3.800094 18.050002)
			(size 0.4572 0.4572)
			(layers "F.Cu" "F.Mask" "F.Paste")
			(net "P5E_PEX2_STN1_TX_DN<20>")
		)
		(pad "BD30" smd circle
			(at 4.750054 18.050002)
			(size 0.4572 0.4572)
			(layers "F.Cu" "F.Mask" "F.Paste")
			(net "GND")
		)
		(pad "BD31" smd circle
			(at 5.700014 18.050002)
			(size 0.4572 0.4572)
			(layers "F.Cu" "F.Mask" "F.Paste")
			(net "P5E_PEX2_STN1_TX_DN<22>")
		)
		(pad "BD32" smd circle
			(at 6.649974 18.050002)
			(size 0.4572 0.4572)
			(layers "F.Cu" "F.Mask" "F.Paste")
			(net "GND")
		)
		(pad "BD33" smd circle
			(at 7.599934 18.050002)
			(size 0.4572 0.4572)
			(layers "F.Cu" "F.Mask" "F.Paste")
			(net "P5E_PEX2_STN1_TX_DN<24>")
		)
		(pad "BD34" smd circle
			(at 8.549894 18.050002)
			(size 0.4572 0.4572)
			(layers "F.Cu" "F.Mask" "F.Paste")
			(net "GND")
		)
		(pad "BD35" smd circle
			(at 9.500108 18.050002)
			(size 0.4572 0.4572)
			(layers "F.Cu" "F.Mask" "F.Paste")
			(net "P5E_PEX2_STN1_TX_DN<26>")
		)
		(pad "BD36" smd circle
			(at 10.450068 18.050002)
			(size 0.4572 0.4572)
			(layers "F.Cu" "F.Mask" "F.Paste")
			(net "GND")
		)
		(pad "BD37" smd circle
			(at 11.400028 18.050002)
			(size 0.4572 0.4572)
			(layers "F.Cu" "F.Mask" "F.Paste")
			(net "P5E_PEX2_STN1_TX_DN<28>")
		)
		(pad "BD38" smd circle
			(at 12.349988 18.050002)
			(size 0.4572 0.4572)
			(layers "F.Cu" "F.Mask" "F.Paste")
			(net "GND")
		)
		(pad "BD39" smd circle
			(at 13.299948 18.050002)
			(size 0.4572 0.4572)
			(layers "F.Cu" "F.Mask" "F.Paste")
			(net "P5E_PEX2_STN1_TX_DN<30>")
		)
		(pad "BD40" smd circle
			(at 14.249908 18.050002)
			(size 0.4572 0.4572)
			(layers "F.Cu" "F.Mask" "F.Paste")
			(net "GND")
		)
		(pad "BD41" smd circle
			(at 15.200122 18.050002)
			(size 0.4572 0.4572)
			(layers "F.Cu" "F.Mask" "F.Paste")
			(net "P5E_PEX2_STN0_TX_DN<15>")
		)
		(pad "BD42" smd circle
			(at 16.150082 18.050002)
			(size 0.4572 0.4572)
			(layers "F.Cu" "F.Mask" "F.Paste")
			(net "GND")
		)
		(pad "BD43" smd circle
			(at 17.100042 18.050002)
			(size 0.4572 0.4572)
			(layers "F.Cu" "F.Mask" "F.Paste")
			(net "P5E_PEX2_STN0_TX_DN<13>")
		)
		(pad "BD44" smd circle
			(at 18.050002 18.050002)
			(size 0.4572 0.4572)
			(layers "F.Cu" "F.Mask" "F.Paste")
			(net "GND")
		)
		(pad "BD45" smd circle
			(at 18.999962 18.050002)
			(size 0.4572 0.4572)
			(layers "F.Cu" "F.Mask" "F.Paste")
			(net "P5E_PEX2_STN0_TX_DN<11>")
		)
		(pad "BD46" smd circle
			(at 19.949922 18.050002)
			(size 0.4572 0.4572)
			(layers "F.Cu" "F.Mask" "F.Paste")
			(net "GND")
		)
		(pad "BD47" smd circle
			(at 20.899882 18.050002)
			(size 0.4572 0.4572)
			(layers "F.Cu" "F.Mask" "F.Paste")
			(net "P5E_PEX2_STN0_TX_DN<9>")
		)
		(pad "BD48" smd circle
			(at 21.850096 18.050002)
			(size 0.4572 0.4572)
			(layers "F.Cu" "F.Mask" "F.Paste")
			(net "GND")
		)
		(pad "BD49" smd circle
			(at 22.800056 18.050002)
			(size 0.4572 0.4572)
			(layers "F.Cu" "F.Mask" "F.Paste")
			(net "GND")
		)
		(pad "BE1" smd circle
			(at -22.800056 18.999962)
			(size 0.4572 0.4572)
			(layers "F.Cu" "F.Mask" "F.Paste")
			(net "Net_1457")
		)
		(pad "BE2" smd circle
			(at -21.850096 18.999962)
			(size 0.4572 0.4572)
			(layers "F.Cu" "F.Mask" "F.Paste")
			(net "Net_1454")
		)
		(pad "BE3" smd circle
			(at -20.899882 18.999962)
			(size 0.4572 0.4572)
			(layers "F.Cu" "F.Mask" "F.Paste")
			(net "GND")
		)
		(pad "BE4" smd circle
			(at -19.949922 18.999962)
			(size 0.4572 0.4572)
			(layers "F.Cu" "F.Mask" "F.Paste")
			(net "GND")
		)
		(pad "BE5" smd circle
			(at -18.999962 18.999962)
			(size 0.4572 0.4572)
			(layers "F.Cu" "F.Mask" "F.Paste")
			(net "GND")
		)
		(pad "BE6" smd circle
			(at -18.050002 18.999962)
			(size 0.4572 0.4572)
			(layers "F.Cu" "F.Mask" "F.Paste")
			(net "GND")
		)
		(pad "BE7" smd circle
			(at -17.100042 18.999962)
			(size 0.4572 0.4572)
			(layers "F.Cu" "F.Mask" "F.Paste")
			(net "GND")
		)
		(pad "BE8" smd circle
			(at -16.150082 18.999962)
			(size 0.4572 0.4572)
			(layers "F.Cu" "F.Mask" "F.Paste")
			(net "GND")
		)
		(pad "BE9" smd circle
			(at -15.200122 18.999962)
			(size 0.4572 0.4572)
			(layers "F.Cu" "F.Mask" "F.Paste")
			(net "GND")
		)
		(pad "BE10" smd circle
			(at -14.249908 18.999962)
			(size 0.4572 0.4572)
			(layers "F.Cu" "F.Mask" "F.Paste")
			(net "GND")
		)
		(pad "BE11" smd circle
			(at -13.299948 18.999962)
			(size 0.4572 0.4572)
			(layers "F.Cu" "F.Mask" "F.Paste")
			(net "GND")
		)
		(pad "BE12" smd circle
			(at -12.349988 18.999962)
			(size 0.4572 0.4572)
			(layers "F.Cu" "F.Mask" "F.Paste")
			(net "GND")
		)
		(pad "BE13" smd circle
			(at -11.400028 18.999962)
			(size 0.4572 0.4572)
			(layers "F.Cu" "F.Mask" "F.Paste")
			(net "GND")
		)
		(pad "BE14" smd circle
			(at -10.450068 18.999962)
			(size 0.4572 0.4572)
			(layers "F.Cu" "F.Mask" "F.Paste")
			(net "GND")
		)
		(pad "BE15" smd circle
			(at -9.500108 18.999962)
			(size 0.4572 0.4572)
			(layers "F.Cu" "F.Mask" "F.Paste")
			(net "GND")
		)
		(pad "BE16" smd circle
			(at -8.549894 18.999962)
			(size 0.4572 0.4572)
			(layers "F.Cu" "F.Mask" "F.Paste")
			(net "GND")
		)
		(pad "BE17" smd circle
			(at -7.599934 18.999962)
			(size 0.4572 0.4572)
			(layers "F.Cu" "F.Mask" "F.Paste")
			(net "GND")
		)
		(pad "BE18" smd circle
			(at -6.649974 18.999962)
			(size 0.4572 0.4572)
			(layers "F.Cu" "F.Mask" "F.Paste")
			(net "GND")
		)
		(pad "BE19" smd circle
			(at -5.700014 18.999962)
			(size 0.4572 0.4572)
			(layers "F.Cu" "F.Mask" "F.Paste")
			(net "GND")
		)
		(pad "BE20" smd circle
			(at -4.750054 18.999962)
			(size 0.4572 0.4572)
			(layers "F.Cu" "F.Mask" "F.Paste")
			(net "GND")
		)
		(pad "BE21" smd circle
			(at -3.800094 18.999962)
			(size 0.4572 0.4572)
			(layers "F.Cu" "F.Mask" "F.Paste")
			(net "GND")
		)
		(pad "BE22" smd circle
			(at -2.84988 18.999962)
			(size 0.4572 0.4572)
			(layers "F.Cu" "F.Mask" "F.Paste")
			(net "GND")
		)
		(pad "BE23" smd circle
			(at -1.89992 18.999962)
			(size 0.4572 0.4572)
			(layers "F.Cu" "F.Mask" "F.Paste")
			(net "GND")
		)
		(pad "BE24" smd circle
			(at -0.94996 18.999962)
			(size 0.4572 0.4572)
			(layers "F.Cu" "F.Mask" "F.Paste")
			(net "GND")
		)
		(pad "BE25" smd circle
			(at 0 18.999962)
			(size 0.4572 0.4572)
			(layers "F.Cu" "F.Mask" "F.Paste")
			(net "GND")
		)
		(pad "BE26" smd circle
			(at 0.94996 18.999962)
			(size 0.4572 0.4572)
			(layers "F.Cu" "F.Mask" "F.Paste")
			(net "GND")
		)
		(pad "BE27" smd circle
			(at 1.89992 18.999962)
			(size 0.4572 0.4572)
			(layers "F.Cu" "F.Mask" "F.Paste")
			(net "GND")
		)
		(pad "BE28" smd circle
			(at 2.84988 18.999962)
			(size 0.4572 0.4572)
			(layers "F.Cu" "F.Mask" "F.Paste")
			(net "GND")
		)
		(pad "BE29" smd circle
			(at 3.800094 18.999962)
			(size 0.4572 0.4572)
			(layers "F.Cu" "F.Mask" "F.Paste")
			(net "GND")
		)
		(pad "BE30" smd circle
			(at 4.750054 18.999962)
			(size 0.4572 0.4572)
			(layers "F.Cu" "F.Mask" "F.Paste")
			(net "GND")
		)
		(pad "BE31" smd circle
			(at 5.700014 18.999962)
			(size 0.4572 0.4572)
			(layers "F.Cu" "F.Mask" "F.Paste")
			(net "GND")
		)
		(pad "BE32" smd circle
			(at 6.649974 18.999962)
			(size 0.4572 0.4572)
			(layers "F.Cu" "F.Mask" "F.Paste")
			(net "GND")
		)
		(pad "BE33" smd circle
			(at 7.599934 18.999962)
			(size 0.4572 0.4572)
			(layers "F.Cu" "F.Mask" "F.Paste")
			(net "GND")
		)
		(pad "BE34" smd circle
			(at 8.549894 18.999962)
			(size 0.4572 0.4572)
			(layers "F.Cu" "F.Mask" "F.Paste")
			(net "GND")
		)
		(pad "BE35" smd circle
			(at 9.500108 18.999962)
			(size 0.4572 0.4572)
			(layers "F.Cu" "F.Mask" "F.Paste")
			(net "GND")
		)
	)
)
